# S9S_MB_2U (Grand Teton) — schematic netlist excerpt (pin names and nets, part order shuffled) for the footprints in the layout excerpt that follows; sources: Cadence DE-HDL packaged netlist, KiCad conversion of 03242023_DA0F0TMBIJ0_F0T_Motherboard_J_brd_V01_OCP.brd

R52  Q_RES  100 1% CHIP  pkg 0402LF  page 47 : A = DBP_CPU1_MBP1_GTL_R_N ; B = DBP_CPU_MBP1_GTL_N
C209  Q_CAP  10UF 6.3V 20% X6S  pkg C0603  page 206 : A = P3V3_DB2000_VDDA ; B = GND

(kicad_pcb
	(version 20260206)
	(generator "pcbnew")
	(generator_version "10.0")
	(general
		(thickness 1.6)
		(legacy_teardrops no)
	)
	(paper "A4")
	(title_block
		(title "03242023_DA0F0TMBIJ0_F0T_Motherboard_J_brd_V01_OCP.brd")
		(comment 1 "Grand Teton / footprints 5992-5993 of 6105")
	)
	(layers
		(0 "F.Cu" signal "TOP")
		(4 "In1.Cu" signal "GND")
		(6 "In2.Cu" signal "IN1")
		(8 "In3.Cu" signal "GND1")
		(10 "In4.Cu" signal "IN2")
		(12 "In5.Cu" signal "GND2")
		(14 "In6.Cu" signal "IN3")
		(16 "In7.Cu" signal "GND3")
		(18 "In8.Cu" signal "VCC")
		(20 "In9.Cu" signal "VCC1")
		(22 "In10.Cu" signal "GND4")
		(24 "In11.Cu" signal "IN4")
		(26 "In12.Cu" signal "GND5")
		(28 "In13.Cu" signal "IN5")
		(30 "In14.Cu" signal "GND6")
		(32 "In15.Cu" signal "IN6")
		(34 "In16.Cu" signal "GND7")
		(2 "B.Cu" signal "BOTTOM")
		(9 "F.Adhes" user "F.Adhesive")
		(11 "B.Adhes" user "B.Adhesive")
		(13 "F.Paste" user "Package Geometry/Pastemask Top")
		(15 "B.Paste" user "Package Geometry/Pastemask Bottom")
		(5 "F.SilkS" user "Ref Des/Silkscreen Top")
		(7 "B.SilkS" user "Ref Des/Silkscreen Bottom")
		(1 "F.Mask" user "Board Geometry/Soldermask Top")
		(3 "B.Mask" user "Board Geometry/Soldermask Bottom")
		(17 "Dwgs.User" user "User.Drawings")
		(19 "Cmts.User" user "User.Comments")
		(21 "Eco1.User" user "User.Eco1")
		(23 "Eco2.User" user "User.Eco2")
		(25 "Edge.Cuts" user "Board Geometry/Outline")
		(27 "Margin" user)
		(31 "F.CrtYd" user "Package Geometry/Place Bound Top")
		(29 "B.CrtYd" user "Package Geometry/Place Bound Bottom")
		(35 "F.Fab" user "Ref Des/Assembly Top")
		(33 "B.Fab" user "Ref Des/Assembly Bottom")
	)
	(footprint ""
		(layer "B.Cu")
		(at 74.347324 -190.705232 90)
		(property "Reference" "R52"
			(at 0 0 90)
			(layer "B.SilkS")
			(hide yes)
			(effects
				(font
					(size 1.27 1.27)
				)
				(justify mirror)
			)
		)
		(property "Value" ""
			(at 0 0 90)
			(layer "B.Fab")
			(effects
				(font
					(size 1.27 1.27)
				)
				(justify mirror)
			)
		)
		(duplicate_pad_numbers_are_jumpers no)
		(fp_line
			(start 0.7874 -0.4064)
			(end -0.7874 -0.4064)
			(stroke
				(width 0.1524)
				(type default)
			)
			(layer "B.SilkS")
		)
		(fp_line
			(start -0.7874 -0.4064)
			(end -0.7874 0.4064)
			(stroke
				(width 0.1524)
				(type default)
			)
			(layer "B.SilkS")
		)
		(fp_line
			(start 0.7874 0.4064)
			(end 0.7874 -0.4064)
			(stroke
				(width 0.1524)
				(type default)
			)
			(layer "B.SilkS")
		)
		(fp_line
			(start -0.7874 0.4064)
			(end 0.7874 0.4064)
			(stroke
				(width 0.1524)
				(type default)
			)
			(layer "B.SilkS")
		)
		(fp_line
			(start 0.67945 -0.305054)
			(end 0.12065 -0.305054)
			(stroke
				(width 0.1)
				(type default)
			)
			(layer "B.Fab")
		)
		(fp_line
			(start 0.12065 -0.305054)
			(end 0.12065 -0.2794)
			(stroke
				(width 0.1)
				(type default)
			)
			(layer "B.Fab")
		)
		(fp_line
			(start -0.12065 -0.3048)
			(end -0.67945 -0.3048)
			(stroke
				(width 0.1)
				(type default)
			)
			(layer "B.Fab")
		)
		(fp_line
			(start -0.67945 -0.3048)
			(end -0.67945 0.3048)
			(stroke
				(width 0.1)
				(type default)
			)
			(layer "B.Fab")
		)
		(fp_line
			(start 0.12065 -0.2794)
			(end -0.12065 -0.2794)
			(stroke
				(width 0.1)
				(type default)
			)
			(layer "B.Fab")
		)
		(fp_line
			(start -0.12065 -0.2794)
			(end -0.12065 -0.3048)
			(stroke
				(width 0.1)
				(type default)
			)
			(layer "B.Fab")
		)
		(fp_line
			(start 0.12065 0.2794)
			(end 0.12065 0.3048)
			(stroke
				(width 0.1)
				(type default)
			)
			(layer "B.Fab")
		)
		(fp_line
			(start -0.120396 0.2794)
			(end 0.12065 0.2794)
			(stroke
				(width 0.1)
				(type default)
			)
			(layer "B.Fab")
		)
		(fp_line
			(start 0.67945 0.3048)
			(end 0.67945 -0.305054)
			(stroke
				(width 0.1)
				(type default)
			)
			(layer "B.Fab")
		)
		(fp_line
			(start 0.12065 0.3048)
			(end 0.67945 0.3048)
			(stroke
				(width 0.1)
				(type default)
			)
			(layer "B.Fab")
		)
		(fp_line
			(start -0.120396 0.3048)
			(end -0.120396 0.2794)
			(stroke
				(width 0.1)
				(type default)
			)
			(layer "B.Fab")
		)
		(fp_line
			(start -0.67945 0.3048)
			(end -0.120396 0.3048)
			(stroke
				(width 0.1)
				(type default)
			)
			(layer "B.Fab")
		)
		(pad "1" smd circle
			(at 0.40005 0 270)
			(size 0 0)
			(layers "B.Cu" "B.Mask" "B.Paste")
			(net "DBP_CPU1_MBP1_GTL_R_N")
		)
		(pad "2" smd circle
			(at -0.40005 0 270)
			(size 0 0)
			(layers "B.Cu" "B.Mask" "B.Paste")
			(net "DBP_CPU_MBP1_GTL_N")
		)
	)
	(footprint ""
		(layer "B.Cu")
		(at 234.894628 -123.015248 90)
		(property "Reference" "C209"
			(at 0 0 90)
			(layer "B.SilkS")
			(hide yes)
			(effects
				(font
					(size 1.27 1.27)
				)
				(justify mirror)
			)
		)
		(property "Value" ""
			(at 0 0 90)
			(layer "B.Fab")
			(effects
				(font
					(size 1.27 1.27)
				)
				(justify mirror)
			)
		)
		(duplicate_pad_numbers_are_jumpers no)
		(fp_line
			(start 1.2954 -0.5842)
			(end -1.2954 -0.5842)
			(stroke
				(width 0.1524)
				(type default)
			)
			(layer "B.SilkS")
		)
		(fp_line
			(start 0 -0.5842)
			(end 0 0.5842)
			(stroke
				(width 0.1524)
				(type default)
			)
			(layer "B.SilkS")
		)
		(fp_line
			(start -1.2954 -0.5842)
			(end -1.2954 0.5842)
			(stroke
				(width 0.1524)
				(type default)
			)
			(layer "B.SilkS")
		)
		(fp_line
			(start 1.2954 0.5842)
			(end 1.2954 -0.5842)
			(stroke
				(width 0.1524)
				(type default)
			)
			(layer "B.SilkS")
		)
		(fp_line
			(start -1.2954 0.5842)
			(end 1.2954 0.5842)
			(stroke
				(width 0.1524)
				(type default)
			)
			(layer "B.SilkS")
		)
		(fp_line
			(start 0.8636 -0.4572)
			(end -0.8636 -0.4572)
			(stroke
				(width 0.1)
				(type default)
			)
			(layer "B.Fab")
		)
		(fp_line
			(start -0.8636 -0.4572)
			(end -0.8636 -0.4064)
			(stroke
				(width 0.1)
				(type default)
			)
			(layer "B.Fab")
		)
		(fp_line
			(start 1.1938 -0.4064)
			(end 0.8636 -0.4064)
			(stroke
				(width 0.1)
				(type default)
			)
			(layer "B.Fab")
		)
		(fp_line
			(start 0.8636 -0.4064)
			(end 0.8636 -0.4572)
			(stroke
				(width 0.1)
				(type default)
			)
			(layer "B.Fab")
		)
		(fp_line
			(start -0.8636 -0.4064)
			(end -1.1938 -0.4064)
			(stroke
				(width 0.1)
				(type default)
			)
			(layer "B.Fab")
		)
		(fp_line
			(start -1.1938 -0.4064)
			(end -1.1938 0.4064)
			(stroke
				(width 0.1)
				(type default)
			)
			(layer "B.Fab")
		)
		(fp_line
			(start 1.1938 0.4064)
			(end 1.1938 -0.4064)
			(stroke
				(width 0.1)
				(type default)
			)
			(layer "B.Fab")
		)
		(fp_line
			(start 0.8636 0.4064)
			(end 1.1938 0.4064)
			(stroke
				(width 0.1)
				(type default)
			)
			(layer "B.Fab")
		)
		(fp_line
			(start -0.8636 0.4064)
			(end -0.8636 0.4572)
			(stroke
				(width 0.1)
				(type default)
			)
			(layer "B.Fab")
		)
		(fp_line
			(start -1.1938 0.4064)
			(end -0.8636 0.4064)
			(stroke
				(width 0.1)
				(type default)
			)
			(layer "B.Fab")
		)
		(fp_line
			(start 0.8636 0.4572)
			(end 0.8636 0.4064)
			(stroke
				(width 0.1)
				(type default)
			)
			(layer "B.Fab")
		)
		(fp_line
			(start -0.8636 0.4572)
			(end 0.8636 0.4572)
			(stroke
				(width 0.1)
				(type default)
			)
			(layer "B.Fab")
		)
		(pad "1" smd rect
			(at 0.7366 0)
			(size 0.7112 0.8128)
			(layers "B.Cu" "B.Mask" "B.Paste")
			(net "P3V3_DB2000_VDDA")
		)
		(pad "2" smd rect
			(at -0.7366 0)
			(size 0.7112 0.8128)
			(layers "B.Cu" "B.Mask" "B.Paste")
			(net "GND")
		)
	)
)
